(kicad_pcb
	(version 20260206)
	(generator "pcbnew")
	(generator_version "10.0")
	(general
		(thickness 1.6)
		(legacy_teardrops no)
	)
	(paper "A4")
	(title_block
		(title "Bryce Canyon_R.DPB_16317-1_OCP.brd")
		(comment 1 "Bryce Canyon / footprints 850-853 of 2099")
	)
	(layers
		(0 "F.Cu" signal "TOP")
		(4 "In1.Cu" signal "L2GND")
		(6 "In2.Cu" signal "L3")
		(8 "In3.Cu" signal "L4VCC")
		(10 "In4.Cu" signal "L5VCC")
		(12 "In5.Cu" signal "L6")
		(14 "In6.Cu" signal "L7GND")
		(2 "B.Cu" signal "BOTTOM")
		(9 "F.Adhes" user "F.Adhesive")
		(11 "B.Adhes" user "B.Adhesive")
		(13 "F.Paste" user "Package Geometry/Pastemask Top")
		(15 "B.Paste" user "Package Geometry/Pastemask Bottom")
		(5 "F.SilkS" user "Ref Des/Silkscreen Top")
		(7 "B.SilkS" user "Ref Des/Silkscreen Bottom")
		(1 "F.Mask" user "Board Geometry/Soldermask Top")
		(3 "B.Mask" user "Board Geometry/Soldermask Bottom")
		(17 "Dwgs.User" user "User.Drawings")
		(19 "Cmts.User" user "User.Comments")
		(21 "Eco1.User" user "User.Eco1")
		(23 "Eco2.User" user "User.Eco2")
		(25 "Edge.Cuts" user "Board Geometry/Outline")
		(27 "Margin" user)
		(31 "F.CrtYd" user "Package Geometry/Place Bound Top")
		(29 "B.CrtYd" user "Package Geometry/Place Bound Bottom")
		(35 "F.Fab" user "Ref Des/Assembly Top")
		(33 "B.Fab" user "Ref Des/Assembly Bottom")
	)
	(footprint ""
		(layer "F.Cu")
		(at 185.950098 -258.910074 -90)
		(property "Reference" "HDDSAS5"
			(at 0 0 270)
			(layer "F.SilkS")
			(hide yes)
			(effects
				(font
					(size 1.27 1.27)
				)
			)
		)
		(property "Value" "SKT-SAS15P-14P-45-GP"
			(at -20.7645 -8.9789 270)
			(unlocked yes)
			(layer "F.Fab")
			(hide yes)
			(effects
				(font
					(size 1.016 1.016)
					(thickness 0.1524)
				)
			)
		)
		(property "Device Type" "10120818-001C-TRLF"
			(at -20.7645 -10.5029 270)
			(unlocked yes)
			(layer "F.Fab")
			(hide yes)
			(effects
				(font
					(size 1.016 1.016)
					(thickness 0.1524)
				)
			)
		)
		(duplicate_pad_numbers_are_jumpers no)
		(fp_line
			(start 1.651 4.2926)
			(end 1.651 3.0099)
			(stroke
				(width 0.1524)
				(type default)
			)
			(layer "F.SilkS")
		)
		(fp_line
			(start 8.509 4.2926)
			(end 1.651 4.2926)
			(stroke
				(width 0.1524)
				(type default)
			)
			(layer "F.SilkS")
		)
		(fp_line
			(start -23.4188 3.0099)
			(end -23.4188 -3.2512)
			(stroke
				(width 0.1524)
				(type default)
			)
			(layer "F.SilkS")
		)
		(fp_line
			(start 1.651 3.0099)
			(end -23.4188 3.0099)
			(stroke
				(width 0.1524)
				(type default)
			)
			(layer "F.SilkS")
		)
		(fp_line
			(start 8.509 3.0099)
			(end 8.509 4.2926)
			(stroke
				(width 0.1524)
				(type default)
			)
			(layer "F.SilkS")
		)
		(fp_line
			(start 23.4188 3.0099)
			(end 8.509 3.0099)
			(stroke
				(width 0.1524)
				(type default)
			)
			(layer "F.SilkS")
		)
		(fp_line
			(start -23.4188 -3.2512)
			(end 23.4188 -3.2512)
			(stroke
				(width 0.1524)
				(type default)
			)
			(layer "F.SilkS")
		)
		(fp_line
			(start 23.4188 -3.2512)
			(end 23.4188 3.0099)
			(stroke
				(width 0.1524)
				(type default)
			)
			(layer "F.SilkS")
		)
		(fp_line
			(start 15.5067 -3.3401)
			(end 16.2687 -3.3401)
			(stroke
				(width 0.3302)
				(type default)
			)
			(layer "F.SilkS")
		)
		(fp_poly
			(pts
				(xy 15.868904 -3.230372) (xy 16.503904 -3.865372) (xy 15.233904 -3.865372)
			)
			(stroke
				(width 0)
				(type default)
			)
			(fill yes)
			(layer "F.SilkS")
		)
		(fp_poly
			(pts
				(xy -22.8727 -2.7559) (xy 22.8727 -2.7559) (xy 22.8727 2.7559) (xy 8.255 2.7559) (xy 8.255 3.5179)
				(xy 1.905 3.5179) (xy 1.905 2.7559) (xy -22.8727 2.7559)
			)
			(stroke
				(width 0)
				(type default)
			)
			(fill no)
			(layer "F.CrtYd")
		)
		(fp_poly
			(pts
				(xy 1.397 4.5466) (xy 1.397 3.2639) (xy -23.6728 3.2639) (xy -23.6728 -3.5052) (xy 23.6728 -3.5052)
				(xy 23.6728 -0.00635) (xy 22.8727 -0.00635) (xy 22.8727 -2.7559) (xy -22.8727 -2.7559) (xy -22.8727 2.7559)
				(xy 1.905 2.7559) (xy 1.905 3.5179) (xy 8.255 3.5179) (xy 8.255 2.7559) (xy 22.8727 2.7559) (xy 22.8727 0.00635)
				(xy 23.6728 0.00635) (xy 23.6728 3.2639) (xy 8.763 3.2639) (xy 8.763 4.5466)
			)
			(stroke
				(width 0)
				(type default)
			)
			(fill no)
			(layer "F.CrtYd")
		)
		(fp_poly
			(pts
				(xy 1.397 4.5466) (xy 1.397 3.2639) (xy -23.6728 3.2639) (xy -23.6728 -3.5052) (xy 23.6728 -3.5052)
				(xy 23.6728 3.2639) (xy 8.763 3.2639) (xy 8.763 4.5466)
			)
			(stroke
				(width 0)
				(type default)
			)
			(fill no)
			(layer "F.Fab")
		)
		(pad "" np_thru_hole circle
			(at -18.874994 0 270)
			(size 0.254 0.254)
			(drill 1.3462)
			(layers "*.Cu" "*.Mask")
			(clearance 0.9017)
			(thermal_gap 0.9017)
		)
		(pad "" np_thru_hole circle
			(at 18.874994 0 270)
			(size 0.254 0.254)
			(drill 0.9398)
			(layers "*.Cu" "*.Mask")
			(clearance 0.6985)
			(thermal_gap 0.6985)
		)
		(pad "G1" smd rect
			(at 21.874988 0 270)
			(size 2.5908 2.5908)
			(layers "F.Cu" "F.Mask" "F.Paste")
			(net "GND")
		)
		(pad "G2" smd rect
			(at -21.874988 0 270)
			(size 2.5908 2.5908)
			(layers "F.Cu" "F.Mask" "F.Paste")
			(net "GND")
		)
		(pad "P1" smd rect
			(at 1.905 -1.82499 270)
			(size 0.6096 2.3622)
			(layers "F.Cu" "F.Mask" "F.Paste")
			(net "Net_1604")
		)
		(pad "P2" smd rect
			(at 0.635 -1.82499 270)
			(size 0.6096 2.3622)
			(layers "F.Cu" "F.Mask" "F.Paste")
			(net "Net_1605")
		)
		(pad "P3" smd rect
			(at -0.635 -1.82499 270)
			(size 0.6096 2.3622)
			(layers "F.Cu" "F.Mask" "F.Paste")
			(net "Net_1606")
		)
		(pad "P4" smd rect
			(at -1.905 -1.82499 270)
			(size 0.6096 2.3622)
			(layers "F.Cu" "F.Mask" "F.Paste")
			(net "GND")
		)
		(pad "P5" smd rect
			(at -3.175 -1.82499 270)
			(size 0.6096 2.3622)
			(layers "F.Cu" "F.Mask" "F.Paste")
			(net "HDD_PRSNT_5")
		)
		(pad "P6" smd rect
			(at -4.445 -1.82499 270)
			(size 0.6096 2.3622)
			(layers "F.Cu" "F.Mask" "F.Paste")
			(net "GND")
		)
		(pad "P7" smd rect
			(at -5.715 -1.82499 270)
			(size 0.6096 2.3622)
			(layers "F.Cu" "F.Mask" "F.Paste")
			(net "5V_PRE_5")
		)
		(pad "P8" smd rect
			(at -6.985 -1.82499 270)
			(size 0.6096 2.3622)
			(layers "F.Cu" "F.Mask" "F.Paste")
			(net "P5V_HDD5")
		)
		(pad "P9" smd rect
			(at -8.255 -1.82499 270)
			(size 0.6096 2.3622)
			(layers "F.Cu" "F.Mask" "F.Paste")
			(net "P5V_HDD5")
		)
		(pad "P10" smd rect
			(at -9.525 -1.82499 270)
			(size 0.6096 2.3622)
			(layers "F.Cu" "F.Mask" "F.Paste")
			(net "GND")
		)
		(pad "P11" smd rect
			(at -10.795 -1.82499 270)
			(size 0.6096 2.3622)
			(layers "F.Cu" "F.Mask" "F.Paste")
			(net "ACT_HDD_5")
		)
		(pad "P12" smd rect
			(at -12.065 -1.82499 270)
			(size 0.6096 2.3622)
			(layers "F.Cu" "F.Mask" "F.Paste")
			(net "GND")
		)
		(pad "P13" smd rect
			(at -13.335 -1.82499 270)
			(size 0.6096 2.3622)
			(layers "F.Cu" "F.Mask" "F.Paste")
			(net "12V_PRE_5")
		)
		(pad "P14" smd rect
			(at -14.605 -1.82499 270)
			(size 0.6096 2.3622)
			(layers "F.Cu" "F.Mask" "F.Paste")
			(net "P12V_HDD5")
		)
		(pad "P15" smd rect
			(at -15.875 -1.82499 270)
			(size 0.6096 2.3622)
			(layers "F.Cu" "F.Mask" "F.Paste")
			(net "P12V_HDD5")
		)
		(pad "S1" smd rect
			(at 15.875 -1.82499 270)
			(size 0.6096 2.3622)
			(layers "F.Cu" "F.Mask" "F.Paste")
			(net "GND")
		)
		(pad "S2" smd rect
			(at 14.605 -1.82499 270)
			(size 0.6096 2.3622)
			(layers "F.Cu" "F.Mask" "F.Paste")
			(net "SAS_HDD_RX_P5")
		)
		(pad "S3" smd rect
			(at 13.335 -1.82499 270)
			(size 0.6096 2.3622)
			(layers "F.Cu" "F.Mask" "F.Paste")
			(net "SAS_HDD_RX_N5")
		)
		(pad "S4" smd rect
			(at 12.065 -1.82499 270)
			(size 0.6096 2.3622)
			(layers "F.Cu" "F.Mask" "F.Paste")
			(net "GND")
		)
		(pad "S5" smd rect
			(at 10.795 -1.82499 270)
			(size 0.6096 2.3622)
			(layers "F.Cu" "F.Mask" "F.Paste")
			(net "PHY_DRV_B_TO_SCC_B_5_DN")
		)
		(pad "S6" smd rect
			(at 9.525 -1.82499 270)
			(size 0.6096 2.3622)
			(layers "F.Cu" "F.Mask" "F.Paste")
			(net "PHY_DRV_B_TO_SCC_B_5_DP")
		)
		(pad "S7" smd rect
			(at 8.255 -1.82499 270)
			(size 0.6096 2.3622)
			(layers "F.Cu" "F.Mask" "F.Paste")
			(net "GND")
		)
		(pad "S8" smd rect
			(at 7.480046 2.845054 270)
			(size 0.508 2.3622)
			(layers "F.Cu" "F.Mask" "F.Paste")
			(net "GND")
		)
		(pad "S9" smd rect
			(at 6.679946 2.845054 270)
			(size 0.508 2.3622)
			(layers "F.Cu" "F.Mask" "F.Paste")
			(net "Net_463")
		)
		(pad "S10" smd rect
			(at 5.8801 2.845054 270)
			(size 0.508 2.3622)
			(layers "F.Cu" "F.Mask" "F.Paste")
			(net "Net_355")
		)
		(pad "S11" smd rect
			(at 5.08 2.845054 270)
			(size 0.508 2.3622)
			(layers "F.Cu" "F.Mask" "F.Paste")
			(net "GND")
		)
		(pad "S12" smd rect
			(at 4.2799 2.845054 270)
			(size 0.508 2.3622)
			(layers "F.Cu" "F.Mask" "F.Paste")
			(net "Net_391")
		)
		(pad "S13" smd rect
			(at 3.480054 2.845054 270)
			(size 0.508 2.3622)
			(layers "F.Cu" "F.Mask" "F.Paste")
			(net "Net_427")
		)
		(pad "S14" smd rect
			(at 2.679954 2.845054 270)
			(size 0.508 2.3622)
			(layers "F.Cu" "F.Mask" "F.Paste")
			(net "GND")
		)
		(zone
			(layer "F.Cu")
			(hatch none 0.5)
			(connect_pads
				(clearance 0)
			)
			(min_thickness 0.25)
			(keepout
				(tracks allowed)
				(vias not_allowed)
				(pads allowed)
				(copperpour not_allowed)
				(footprints allowed)
			)
			(placement
				(enabled no)
				(sheetname "")
			)
			(fill
				(thermal_gap 0.5)
				(thermal_bridge_width 0.5)
				(island_removal_mode 0)
			)
			(polygon
				(pts
					(xy 189.607698 -275.648674) (xy 182.533798 -275.648674) (xy 182.533798 -282.582874) (xy 183.638698 -282.582874)
					(xy 183.638698 -278.468074) (xy 188.261498 -278.468074) (xy 188.261498 -282.582874) (xy 189.607698 -282.582874)
				)
			)
		)
		(zone
			(layer "F.Cu")
			(hatch none 0.5)
			(connect_pads
				(clearance 0)
			)
			(min_thickness 0.25)
			(keepout
				(tracks not_allowed)
				(vias allowed)
				(pads allowed)
				(copperpour not_allowed)
				(footprints allowed)
			)
			(placement
				(enabled no)
				(sheetname "")
			)
			(fill
				(thermal_gap 0.5)
				(thermal_bridge_width 0.5)
				(island_removal_mode 0)
			)
			(polygon
				(pts
					(xy 189.607698 -275.648674) (xy 182.533798 -275.648674) (xy 182.533798 -282.582874) (xy 183.638698 -282.582874)
					(xy 183.638698 -278.468074) (xy 188.261498 -278.468074) (xy 188.261498 -282.582874) (xy 189.607698 -282.582874)
				)
			)
		)
		(zone
			(layer "F.Cu")
			(hatch none 0.5)
			(connect_pads
				(clearance 0)
			)
			(min_thickness 0.25)
			(keepout
				(tracks allowed)
				(vias not_allowed)
				(pads allowed)
				(copperpour not_allowed)
				(footprints allowed)
			)
			(placement
				(enabled no)
				(sheetname "")
			)
			(fill
				(thermal_gap 0.5)
				(thermal_bridge_width 0.5)
				(island_removal_mode 0)
			)
			(polygon
				(pts
					(xy 189.607698 -242.171474) (xy 182.533798 -242.171474) (xy 182.533798 -235.237274) (xy 183.638698 -235.237274)
					(xy 183.638698 -239.352074) (xy 188.261498 -239.352074) (xy 188.261498 -235.237274) (xy 189.607698 -235.237274)
				)
			)
		)
		(zone
			(layer "F.Cu")
			(hatch none 0.5)
			(connect_pads
				(clearance 0)
			)
			(min_thickness 0.25)
			(keepout
				(tracks not_allowed)
				(vias allowed)
				(pads allowed)
				(copperpour not_allowed)
				(footprints allowed)
			)
			(placement
				(enabled no)
				(sheetname "")
			)
			(fill
				(thermal_gap 0.5)
				(thermal_bridge_width 0.5)
				(island_removal_mode 0)
			)
			(polygon
				(pts
					(xy 189.607698 -242.171474) (xy 182.533798 -242.171474) (xy 182.533798 -235.237274) (xy 183.638698 -235.237274)
					(xy 183.638698 -239.352074) (xy 188.261498 -239.352074) (xy 188.261498 -235.237274) (xy 189.607698 -235.237274)
				)
			)
		)
		(zone
			(layers "F.Cu" "B.Cu" "In1.Cu" "In2.Cu" "In3.Cu" "In4.Cu" "In5.Cu" "In6.Cu")
			(hatch none 0.5)
			(connect_pads
				(clearance 0)
			)
			(min_thickness 0.25)
			(keepout
				(tracks not_allowed)
				(vias allowed)
				(pads allowed)
				(copperpour not_allowed)
				(footprints allowed)
			)
			(placement
				(enabled no)
				(sheetname "")
			)
			(fill
				(thermal_gap 0.5)
				(thermal_bridge_width 0.5)
				(island_removal_mode 0)
			)
			(polygon
				(pts
					(arc
						(start 186.724798 -240.03508)
						(mid 185.175398 -240.03508)
						(end 186.724798 -240.03508)
					)
				)
			)
		)
		(zone
			(layers "F.Cu" "B.Cu" "In1.Cu" "In2.Cu" "In3.Cu" "In4.Cu" "In5.Cu" "In6.Cu")
			(hatch none 0.5)
			(connect_pads
				(clearance 0)
			)
			(min_thickness 0.25)
			(keepout
				(tracks not_allowed)
				(vias allowed)
				(pads allowed)
				(copperpour not_allowed)
				(footprints allowed)
			)
			(placement
				(enabled no)
				(sheetname "")
			)
			(fill
				(thermal_gap 0.5)
				(thermal_bridge_width 0.5)
				(island_removal_mode 0)
			)
			(polygon
				(pts
					(arc
						(start 186.927998 -277.785068)
						(mid 184.972198 -277.785068)
						(end 186.927998 -277.785068)
					)
				)
			)
		)
	)
	(footprint ""
		(layer "F.Cu")
		(at 133.731 -372.618 90)
		(property "Reference" "R941"
			(at 0 0 90)
			(layer "F.SilkS")
			(hide yes)
			(effects
				(font
					(size 1.27 1.27)
				)
			)
		)
		(property "Value" "10KR2F-2-GP"
			(at 0.064008 -3.993896 90)
			(unlocked yes)
			(layer "F.Fab")
			(hide yes)
			(effects
				(font
					(size 1.016 1.016)
					(thickness 0.1524)
				)
			)
		)
		(property "Device Type" "R402H16"
			(at 0.064008 -5.517896 90)
			(unlocked yes)
			(layer "F.Fab")
			(hide yes)
			(effects
				(font
					(size 1.016 1.016)
					(thickness 0.1524)
				)
			)
		)
		(duplicate_pad_numbers_are_jumpers no)
		(fp_line
			(start 0.508 -0.9398)
			(end -0.508 -0.9398)
			(stroke
				(width 0.1524)
				(type default)
			)
			(layer "F.SilkS")
		)
		(fp_line
			(start -0.508 -0.9398)
			(end -0.508 0.9398)
			(stroke
				(width 0.1524)
				(type default)
			)
			(layer "F.SilkS")
		)
		(fp_rect
			(start -0.508 0.9398)
			(end 0.508 -0.9398)
			(stroke
				(width 0)
				(type default)
			)
			(fill no)
			(layer "F.CrtYd")
		)
		(fp_rect
			(start -0.508 0.9398)
			(end 0.508 -0.9398)
			(stroke
				(width 0)
				(type default)
			)
			(fill no)
			(layer "F.Fab")
		)
		(pad "1" smd custom
			(at 0 -0.4445 90)
			(size 0.1397 0.1397)
			(layers "F.Cu" "F.Mask" "F.Paste")
			(net "GND")
			(options
				(clearance outline)
				(anchor circle)
			)
			(primitives
				(gr_poly
					(pts
						(arc
							(start -0.1778 -0.2794)
							(mid -0.249642 -0.249642)
							(end -0.2794 -0.1778)
						)
						(arc
							(start -0.2794 0.1778)
							(mid -0.249642 0.249642)
							(end -0.1778 0.2794)
						)
						(arc
							(start 0.1778 0.2794)
							(mid 0.249642 0.249642)
							(end 0.2794 0.1778)
						)
						(arc
							(start 0.2794 -0.1778)
							(mid 0.249642 -0.249642)
							(end 0.1778 -0.2794)
						)
					)
					(width 0)
					(fill yes)
				)
			)
		)
		(pad "2" smd custom
			(at 0 0.4445 90)
			(size 0.1397 0.1397)
			(layers "F.Cu" "F.Mask" "F.Paste")
			(net "FANTACH_F1")
			(options
				(clearance outline)
				(anchor circle)
			)
			(primitives
				(gr_poly
					(pts
						(arc
							(start -0.1778 -0.2794)
							(mid -0.249642 -0.249642)
							(end -0.2794 -0.1778)
						)
						(arc
							(start -0.2794 0.1778)
							(mid -0.249642 0.249642)
							(end -0.1778 0.2794)
						)
						(arc
							(start 0.1778 0.2794)
							(mid 0.249642 0.249642)
							(end 0.2794 0.1778)
						)
						(arc
							(start 0.2794 -0.1778)
							(mid 0.249642 -0.249642)
							(end 0.1778 -0.2794)
						)
					)
					(width 0)
					(fill yes)
				)
			)
		)
	)
	(footprint ""
		(layer "F.Cu")
		(at 478.79 -33.147)
		(property "Reference" "R874"
			(at 0 0 0)
			(layer "F.SilkS")
			(hide yes)
			(effects
				(font
					(size 1.27 1.27)
				)
			)
		)
		(property "Value" "2R6F-GP"
			(at -0.0508 -4.8514 0)
			(unlocked yes)
			(layer "F.Fab")
			(hide yes)
			(effects
				(font
					(size 1.016 1.016)
					(thickness 0.1524)
				)
			)
		)
		(property "Device Type" "R1206H26"
			(at 0 -6.3754 0)
			(unlocked yes)
			(layer "F.Fab")
			(hide yes)
			(effects
				(font
					(size 1.016 1.016)
					(thickness 0.1524)
				)
			)
		)
		(duplicate_pad_numbers_are_jumpers no)
		(fp_line
			(start -1.016 -2.2352)
			(end 1.016 -2.2352)
			(stroke
				(width 0.1524)
				(type default)
			)
			(layer "F.SilkS")
		)
		(fp_line
			(start -1.016 2.2352)
			(end -1.016 -2.2352)
			(stroke
				(width 0.1524)
				(type default)
			)
			(layer "F.SilkS")
		)
		(fp_line
			(start 1.016 -2.2352)
			(end 1.016 2.2352)
			(stroke
				(width 0.1524)
				(type default)
			)
			(layer "F.SilkS")
		)
		(fp_line
			(start 1.016 2.2352)
			(end -1.016 2.2352)
			(stroke
				(width 0.1524)
				(type default)
			)
			(layer "F.SilkS")
		)
		(fp_rect
			(start -1.0922 2.3114)
			(end 1.0922 -2.3114)
			(stroke
				(width 0)
				(type default)
			)
			(fill no)
			(layer "F.CrtYd")
		)
		(fp_poly
			(pts
				(xy -1.0922 -2.3114) (xy 1.0922 -2.3114) (xy 1.0922 2.3114) (xy -1.0922 2.3114)
			)
			(stroke
				(width 0)
				(type default)
			)
			(fill no)
			(layer "F.Fab")
		)
		(pad "1" smd rect
			(at 0 -1.397)
			(size 1.651 1.27)
			(layers "F.Cu" "F.Mask" "F.Paste")
			(net "P5V_HDD35")
		)
		(pad "2" smd rect
			(at 0 1.397)
			(size 1.651 1.27)
			(layers "F.Cu" "F.Mask" "F.Paste")
			(net "5V_PRE_35")
		)
	)
	(footprint ""
		(layer "F.Cu")
		(at 364.744 -128.651 180)
		(property "Reference" "R515"
			(at 0 0 180)
			(layer "F.SilkS")
			(hide yes)
			(effects
				(font
					(size 1.27 1.27)
				)
			)
		)
		(property "Value" "1KR2F-3-GP"
			(at 0.064008 -3.993896 180)
			(unlocked yes)
			(layer "F.Fab")
			(hide yes)
			(effects
				(font
					(size 1.016 1.016)
					(thickness 0.1524)
				)
			)
		)
		(property "Device Type" "R402H16"
			(at 0.064008 -5.517896 180)
			(unlocked yes)
			(layer "F.Fab")
			(hide yes)
			(effects
				(font
					(size 1.016 1.016)
					(thickness 0.1524)
				)
			)
		)
		(duplicate_pad_numbers_are_jumpers no)
		(fp_line
			(start 0.508 -0.9398)
			(end -0.508 -0.9398)
			(stroke
				(width 0.1524)
				(type default)
			)
			(layer "F.SilkS")
		)
		(fp_line
			(start -0.508 -0.9398)
			(end -0.508 0.9398)
			(stroke
				(width 0.1524)
				(type default)
			)
			(layer "F.SilkS")
		)
		(fp_rect
			(start -0.508 0.9398)
			(end 0.508 -0.9398)
			(stroke
				(width 0)
				(type default)
			)
			(fill no)
			(layer "F.CrtYd")
		)
		(fp_rect
			(start -0.508 0.9398)
			(end 0.508 -0.9398)
			(stroke
				(width 0)
				(type default)
			)
			(fill no)
			(layer "F.Fab")
		)
		(pad "1" smd custom
			(at 0 -0.4445 180)
			(size 0.1397 0.1397)
			(layers "F.Cu" "F.Mask" "F.Paste")
			(net "P3V3_STBY_B")
			(options
				(clearance outline)
				(anchor circle)
			)
			(primitives
				(gr_poly
					(pts
						(arc
							(start -0.1778 -0.2794)
							(mid -0.249642 -0.249642)
							(end -0.2794 -0.1778)
						)
						(arc
							(start -0.2794 0.1778)
							(mid -0.249642 0.249642)
							(end -0.1778 0.2794)
						)
						(arc
							(start 0.1778 0.2794)
							(mid 0.249642 0.249642)
							(end 0.2794 0.1778)
						)
						(arc
							(start 0.2794 -0.1778)
							(mid 0.249642 -0.249642)
							(end 0.1778 -0.2794)
						)
					)
					(width 0)
					(fill yes)
				)
			)
		)
		(pad "2" smd custom
			(at 0 0.4445 180)
			(size 0.1397 0.1397)
			(layers "F.Cu" "F.Mask" "F.Paste")
			(net "SW_PWR_R_HDD19")
			(options
				(clearance outline)
				(anchor circle)
			)
			(primitives
				(gr_poly
					(pts
						(arc
							(start -0.1778 -0.2794)
							(mid -0.249642 -0.249642)
							(end -0.2794 -0.1778)
						)
						(arc
							(start -0.2794 0.1778)
							(mid -0.249642 0.249642)
							(end -0.1778 0.2794)
						)
						(arc
							(start 0.1778 0.2794)
							(mid 0.249642 0.249642)
							(end 0.2794 0.1778)
						)
						(arc
							(start 0.2794 -0.1778)
							(mid 0.249642 -0.249642)
							(end 0.1778 -0.2794)
						)
					)
					(width 0)
					(fill yes)
				)
			)
		)
	)
)
